# TIMECARD (Time Appliance Project (Time Card)) — schematic netlist excerpt (pin names and nets, part order shuffled) for the footprints in the layout excerpt that follows; sources: Cadence DE-HDL packaged netlist, KiCad conversion of R4006-B0001-02_R01.brd

R461  RESISTOR  33OHM 1%  pkg SMC_0402R_H016  page 24 : \1\ = FPGA_OUT_MUX2_SEL ; \2\ = MUX2_SEL
R354  RESISTOR  33OHM 1%  pkg SMC_0402R_H016  page 9 : \1\ = FPGA_OUT_I2C_BUFFER_EN ; \2\ = UNNAMED_3_G2201019801_I100_EN

(kicad_pcb
	(version 20260206)
	(generator "pcbnew")
	(generator_version "10.0")
	(general
		(thickness 1.6)
		(legacy_teardrops no)
	)
	(paper "A4")
	(title_block
		(title "timecard-production-celestica-r4006 — R4006-B0001-02_R01.brd")
		(comment 1 "Time Appliance Project (Time Card) / footprints 220-221 of 1113")
	)
	(layers
		(0 "F.Cu" signal "TOP")
		(4 "In1.Cu" signal "L02_GND1")
		(6 "In2.Cu" signal "L03_SIG1")
		(8 "In3.Cu" signal "L04_GND2")
		(10 "In4.Cu" signal "L05_VCC1")
		(12 "In5.Cu" signal "L06_VCC2")
		(14 "In6.Cu" signal "L07_GND3")
		(16 "In7.Cu" signal "L08_SIG2")
		(18 "In8.Cu" signal "L09_GND4")
		(2 "B.Cu" signal "BOTTOM")
		(9 "F.Adhes" user "F.Adhesive")
		(11 "B.Adhes" user "B.Adhesive")
		(13 "F.Paste" user "Package Geometry/Pastemask Top")
		(15 "B.Paste" user "Package Geometry/Pastemask Bottom")
		(5 "F.SilkS" user "Ref Des/Silkscreen Top")
		(7 "B.SilkS" user "Ref Des/Silkscreen Bottom")
		(1 "F.Mask" user "Board Geometry/Soldermask Top")
		(3 "B.Mask" user "Board Geometry/Soldermask Bottom")
		(17 "Dwgs.User" user "User.Drawings")
		(19 "Cmts.User" user "User.Comments")
		(21 "Eco1.User" user "User.Eco1")
		(23 "Eco2.User" user "User.Eco2")
		(25 "Edge.Cuts" user "Board Geometry/Outline")
		(27 "Margin" user)
		(31 "F.CrtYd" user "Package Geometry/Place Bound Top")
		(29 "B.CrtYd" user "Package Geometry/Place Bound Bottom")
		(35 "F.Fab" user "Ref Des/Assembly Top")
		(33 "B.Fab" user "Ref Des/Assembly Bottom")
	)
	(footprint ""
		(layer "F.Cu")
		(at 50.74158 -15.5194 -90)
		(property "Reference" "R354"
			(at -3.4036 -0.09779 90)
			(unlocked yes)
			(layer "F.SilkS")
			(effects
				(font
					(size 0.7874 0.5842)
					(thickness 0.1524)
				)
			)
		)
		(property "Value" "VAL*"
			(at 0.02032 2.13233 270)
			(unlocked yes)
			(layer "F.Fab")
			(hide yes)
			(effects
				(font
					(size 0.7874 0.5842)
					(thickness 0.1524)
				)
			)
		)
		(property "Tolerance" "TOL*"
			(at 0.044704 3.05435 270)
			(unlocked yes)
			(layer "Cmts.User")
			(hide yes)
			(effects
				(font
					(size 0.7874 0.5842)
					(thickness 0.1524)
				)
			)
		)
		(property "User Part Number" "PARTNUM*"
			(at 0.02032 4.024884 270)
			(unlocked yes)
			(layer "Cmts.User")
			(hide yes)
			(effects
				(font
					(size 0.7874 0.5842)
					(thickness 0.1524)
				)
			)
		)
		(property "Device Type" "RESISTOR-G155-133R0-01,33OHM,1%"
			(at 0.008382 1.210564 270)
			(unlocked yes)
			(layer "F.Fab")
			(hide yes)
			(effects
				(font
					(size 0.7874 0.5842)
					(thickness 0.1524)
				)
			)
		)
		(duplicate_pad_numbers_are_jumpers no)
		(fp_line
			(start -1.143 0.5588)
			(end 1.143 0.5588)
			(stroke
				(width 0.1)
				(type default)
			)
			(layer "F.SilkS")
		)
		(fp_line
			(start 1.143 0.5588)
			(end 1.143 -0.5588)
			(stroke
				(width 0.1)
				(type default)
			)
			(layer "F.SilkS")
		)
		(fp_line
			(start -1.143 -0.5588)
			(end -1.143 0.5588)
			(stroke
				(width 0.1)
				(type default)
			)
			(layer "F.SilkS")
		)
		(fp_line
			(start 1.143 -0.5588)
			(end -1.143 -0.5588)
			(stroke
				(width 0.1)
				(type default)
			)
			(layer "F.SilkS")
		)
		(fp_rect
			(start 1.143 0.5588)
			(end -1.143 -0.5588)
			(stroke
				(width 0)
				(type default)
			)
			(fill no)
			(layer "F.CrtYd")
		)
		(fp_line
			(start -0.508 0.3048)
			(end 0.508 0.3048)
			(stroke
				(width 0.1)
				(type default)
			)
			(layer "F.Fab")
		)
		(fp_line
			(start 0.508 0.3048)
			(end 0.508 -0.3048)
			(stroke
				(width 0.1)
				(type default)
			)
			(layer "F.Fab")
		)
		(fp_line
			(start -0.508 -0.3048)
			(end -0.508 0.3048)
			(stroke
				(width 0.1)
				(type default)
			)
			(layer "F.Fab")
		)
		(fp_line
			(start 0.508 -0.3048)
			(end -0.508 -0.3048)
			(stroke
				(width 0.1)
				(type default)
			)
			(layer "F.Fab")
		)
		(pad "1" smd rect
			(at -0.5334 0 270)
			(size 0.7112 0.6096)
			(layers "F.Cu" "F.Mask" "F.Paste")
			(net "FPGA_OUT_I2C_BUFFER_EN")
		)
		(pad "2" smd rect
			(at 0.5334 0 270)
			(size 0.7112 0.6096)
			(layers "F.Cu" "F.Mask" "F.Paste")
			(net "UNNAMED_3_G2201019801_I100_EN")
		)
		(zone
			(layer "F.Cu")
			(hatch none 0.5)
			(connect_pads
				(clearance 0)
			)
			(min_thickness 0.25)
			(keepout
				(tracks allowed)
				(vias not_allowed)
				(pads allowed)
				(copperpour not_allowed)
				(footprints allowed)
			)
			(placement
				(enabled no)
				(sheetname "")
			)
			(fill
				(thermal_gap 0.5)
				(thermal_bridge_width 0.5)
				(island_removal_mode 0)
			)
			(polygon
				(pts
					(xy 50.43678 -15.4432) (xy 51.04638 -15.4432) (xy 51.04638 -15.5956) (xy 50.43678 -15.5956)
				)
			)
		)
	)
	(footprint ""
		(layer "F.Cu")
		(at 101.4476 -83.5914)
		(property "Reference" "R461"
			(at -2.5146 -0.69723 0)
			(unlocked yes)
			(layer "F.SilkS")
			(effects
				(font
					(size 0.7874 0.5842)
					(thickness 0.1524)
				)
			)
		)
		(property "Value" "VAL*"
			(at 0.02032 2.13233 0)
			(unlocked yes)
			(layer "F.Fab")
			(hide yes)
			(effects
				(font
					(size 0.7874 0.5842)
					(thickness 0.1524)
				)
			)
		)
		(property "Tolerance" "TOL*"
			(at 0.044704 3.05435 0)
			(unlocked yes)
			(layer "Cmts.User")
			(hide yes)
			(effects
				(font
					(size 0.7874 0.5842)
					(thickness 0.1524)
				)
			)
		)
		(property "User Part Number" "PARTNUM*"
			(at 0.02032 4.024884 0)
			(unlocked yes)
			(layer "Cmts.User")
			(hide yes)
			(effects
				(font
					(size 0.7874 0.5842)
					(thickness 0.1524)
				)
			)
		)
		(property "Device Type" "RESISTOR-G155-133R0-01,33OHM,1%"
			(at 0.008382 1.210564 0)
			(unlocked yes)
			(layer "F.Fab")
			(hide yes)
			(effects
				(font
					(size 0.7874 0.5842)
					(thickness 0.1524)
				)
			)
		)
		(duplicate_pad_numbers_are_jumpers no)
		(fp_line
			(start -1.143 -0.5588)
			(end -1.143 0.5588)
			(stroke
				(width 0.1)
				(type default)
			)
			(layer "F.SilkS")
		)
		(fp_line
			(start -1.143 0.5588)
			(end 1.143 0.5588)
			(stroke
				(width 0.1)
				(type default)
			)
			(layer "F.SilkS")
		)
		(fp_line
			(start 1.143 -0.5588)
			(end -1.143 -0.5588)
			(stroke
				(width 0.1)
				(type default)
			)
			(layer "F.SilkS")
		)
		(fp_line
			(start 1.143 0.5588)
			(end 1.143 -0.5588)
			(stroke
				(width 0.1)
				(type default)
			)
			(layer "F.SilkS")
		)
		(fp_poly
			(pts
				(xy -1.143 0.5588) (xy 1.143 0.5588) (xy 1.143 -0.5588) (xy -1.143 -0.5588)
			)
			(stroke
				(width 0)
				(type default)
			)
			(fill no)
			(layer "F.CrtYd")
		)
		(fp_line
			(start -0.508 -0.3048)
			(end -0.508 0.3048)
			(stroke
				(width 0.1)
				(type default)
			)
			(layer "F.Fab")
		)
		(fp_line
			(start -0.508 0.3048)
			(end 0.508 0.3048)
			(stroke
				(width 0.1)
				(type default)
			)
			(layer "F.Fab")
		)
		(fp_line
			(start 0.508 -0.3048)
			(end -0.508 -0.3048)
			(stroke
				(width 0.1)
				(type default)
			)
			(layer "F.Fab")
		)
		(fp_line
			(start 0.508 0.3048)
			(end 0.508 -0.3048)
			(stroke
				(width 0.1)
				(type default)
			)
			(layer "F.Fab")
		)
		(pad "1" smd rect
			(at -0.5334 0)
			(size 0.7112 0.6096)
			(layers "F.Cu" "F.Mask" "F.Paste")
			(net "FPGA_OUT_MUX2_SEL")
		)
		(pad "2" smd rect
			(at 0.5334 0)
			(size 0.7112 0.6096)
			(layers "F.Cu" "F.Mask" "F.Paste")
			(net "MUX2_SEL")
		)
		(zone
			(layer "F.Cu")
			(hatch none 0.5)
			(connect_pads
				(clearance 0)
			)
			(min_thickness 0.25)
			(keepout
				(tracks allowed)
				(vias not_allowed)
				(pads allowed)
				(copperpour not_allowed)
				(footprints allowed)
			)
			(placement
				(enabled no)
				(sheetname "")
			)
			(fill
				(thermal_gap 0.5)
				(thermal_bridge_width 0.5)
				(island_removal_mode 0)
			)
			(polygon
				(pts
					(xy 101.3714 -83.2866) (xy 101.5238 -83.2866) (xy 101.5238 -83.8962) (xy 101.3714 -83.8962)
				)
			)
		)
		(zone
			(layer "F.Cu")
			(hatch none 0.5)
			(connect_pads
				(clearance 0)
			)
			(min_thickness 0.25)
			(keepout
				(tracks not_allowed)
				(vias allowed)
				(pads allowed)
				(copperpour not_allowed)
				(footprints allowed)
			)
			(placement
				(enabled no)
				(sheetname "")
			)
			(fill
				(thermal_gap 0.5)
				(thermal_bridge_width 0.5)
				(island_removal_mode 0)
			)
			(polygon
				(pts
					(xy 101.3714 -83.2866) (xy 101.5238 -83.2866) (xy 101.5238 -83.8962) (xy 101.3714 -83.8962)
				)
			)
		)
	)
)
